# BASEBOARD_FAB2 (Tioga Pass) — schematic parts with pin connectivity, parts 4676–4676 of 4751; source: Cadence DE-HDL packaged netlist (pstxprt.dat, pstxnet.dat, pstchip.dat)

U7C1  LBG_CORE_QAT_EXT_D  IC  pkg BGA1  page 114  (pins 625-936 of 1310)
  BH20  GPP_B9_SRCCLKREQ4_N  BI  = FM_PWR_BTN_N
  BH24  RSVD(26)  UNSPEC  = TP_PCH_RSVD26
  BH27  VSS(90)  GROUND  = GND
  BH31  LAN_RX_P0N  BI  = KR_P0_OCP_RX_C_DN
  BH35  LAN_RX_P3P  BI  = NC
  BH38  VSS(89)  GROUND  = GND
  BH42  VSS(88)  GROUND  = GND
  BH46  VSS(87)  GROUND  = GND
  BH50  GPP_E0_SATAXPCIE0_SATAGP0  BI  = FM_CPU0_RC_ERROR_R1_N
  BH54  VSS(86)  GROUND  = GND
  BH58  USB3_4_TXN  BI  = TP_USB3_P04_TXN
  BH61  USB3_10_PCIE3_GBE_TXN  BI  = P3E_PCH_M2_TX_DN<3>
  BH65  PCIE5_GBE_TXN  BI  = PE_PCH_SPRV_TX_DN
  BH69  USB3_3_RXP  BI  = TP_USB3_P03_RXP
  BH71  USB3_3_RXN  BI  = TP_USB3_P03_RXN
  BJ1  VSS(85)  GROUND  = GND
  BJ3  VSS(78)  GROUND  = GND
  BJ5  VSS(83)  GROUND  = GND
  BJ7  VSS(82)  GROUND  = GND
  BJ11  VSS(84)  GROUND  = GND
  BJ15  VSS(81)  GROUND  = GND
  BJ18  VSS(80)  GROUND  = GND
  BJ22  GPP_B20  BI  = FM_BIOS_POST_CMPLT_N
  BJ26  VSS(79)  GROUND  = GND
  BJ29  LAN_RX_P1P  BI  = KR_P1_OCP_RX_C_DP
  BJ33  VSS(77)  GROUND  = GND
  BJ37  LAN_RX_P2N  BI  = NC
  BJ40  RSVD(41)  UNSPEC  = TP_PCH_RSVD41
  BJ44  GPP_D2  BI  = IRQ_HSC_FAULT_N
  BJ48  GPP_E7_CPU_GP1  BI  = FM_ADR_SMI_GPIO_N
  BJ52  VSS(76)  GROUND  = GND
  BJ56  USB3_2_TXP  BI  = TP_USB3_P02_TXP
  BJ59  USB3_5_TXP  BI  = TP_USB3_P05_TXP
  BJ63  PCIE5_GBE_TXP  BI  = PE_PCH_SPRV_TX_DP
  BJ66  PCIE4_GBE_TXP  BI  = P2E_SSB_BMC_TX_DP
  BJ68  VSS(75)  GROUND  = GND
  BJ70  USB3_2_RXP  BI  = TP_USB3_P02_RXP
  BJ72  USB3_2_RXN  BI  = TP_USB3_P02_RXN
  BK2  GPP_J3_LAN_LED_P1_1  BI  = LED_GBE_P1_1
  BK4  GPP_J1_LAN_LED_P0_1  BI  = LED_GBE_P0_1
  BK9  GPP_B11  BI  = FM_PMBUS_ALERT_BUF_EN_R2_N
  BK13  GPP_B15  BI  = FM_UART_ALERT_N
  BK17  GPP_B5_SRCCLKREQ0_N  BI  = IRQ_PVDDQ_DEF_VRHOT_LVT3_N
  BK20  GPP_B19  BI  = FM_BIOS_PREFRB2_GOOD
  BK24  VSS(74)  GROUND  = GND
  BK27  VSS(73)  GROUND  = GND
  BK31  VSS(72)  GROUND  = GND
  BK35  VSS(71)  GROUND  = GND
  BK38  VSS(70)  GROUND  = GND
  BK42  VSS(69)  GROUND  = GND
  BK46  GPP_D1  BI  = FM_PWR_LED_N
  BK50  VSS(68)  GROUND  = GND
  BK54  USB3_1_TXP  BI  = USB3_P01_TXP
  BK58  USB3_5_TXN  BI  = TP_USB3_P05_TXN
  BK61  USB3_10_PCIE3_GBE_TXP  BI  = P3E_PCH_M2_TX_DP<3>
  BK65  USB3_9_PCIE2_TXN  BI  = P3E_PCH_M2_TX_DN<2>
  BK69  USB3_1_RXP  BI  = USB3_P01_RXP
  BK71  USB3_1_RXN  BI  = USB3_P01_RXN
  BL1  GPP_J0_LAN_LED_P0_0  BI  = LED_GBE_P0_0
  BL3  GPP_J4_LAN_LED_P2_0  BI  = LED_GBE_P2_0
  BL5  VSS(63)  GROUND  = GND
  BL7  GPP_B0_CORE_VID0  BI  = VID_PCH_CORE_PVNN_AUX_VID_0
  BL11  GPP_B10_SRCCLKREQ5_N  BI  = RST_SYSTEM_BTN_N
  BL15  GPP_B18  BI  = FM_UV_ADR_TRIGGER_EN
  BL18  GPP_B12_GLB_RST_WARN_N  BI  = FM_GLOBAL_RST_WARN_N
  BL22  VSS(67)  GROUND  = GND
  BL26  RSVD(39)  UNSPEC  = TP_10GBE_KR0_MON_DN
  BL29  RSVD(38)  UNSPEC  = TP_PCH_RSVD38
  BL33  RSVD(43)  UNSPEC  = TP_10GBE_KR1_MON_DN
  BL37  VSS(64)  GROUND  = GND
  BL40  VSS(66)  GROUND  = GND
  BL44  GPP_D14_SML0BDATA_IE  BI  = SMB_SLOTX24_PCH_STBY_LVC3_SDA
  BL48  GPP_E9_USB2_OC0_N  BI  = FM_OC0_USB_N
  BL52  USB3_1_TXN  BI  = USB3_P01_TXN
  BL56  USB3_2_TXN  BI  = TP_USB3_P02_TXN
  BL59  USB3_6_TXN  BI  = TP_USB3_P06_TXN
  BL63  VSS(62)  GROUND  = GND
  BL66  USB3_9_PCIE2_TXP  BI  = P3E_PCH_M2_TX_DP<2>
  BL68  VSS(65)  GROUND  = GND
  BL70  VSS(61)  GROUND  = GND
  BL72  VSS(60)  GROUND  = GND
  BM2  GPP_J7_LAN_LED_P3_1  BI  = LED_GBE_P3_1
  BM4  GPP_J8_LAN_I2C_SCL_MDC_P0  BI  = SMB_PCH_MEZZ_LOM0_SCL
  BM9  VSS(51)  GROUND  = GND
  BM13  VSS(59)  GROUND  = GND
  BM17  VSS(58)  GROUND  = GND
  BM20  GPP_B23_MEIE_SML1ALRT_N_PHOT_N  BI  = FM_PCH_BMC_THERMTRIP_EXI_STRAP_
  BM24  LAN_TX_P1N  BI  = KR_P1_OCP_TX_DN
  BM27  LAN_TX_P0N  BI  = KR_P0_OCP_TX_DN
  BM31  LAN_TX_P3P  BI  = NC
  BM35  LAN_TX_P2N  BI  = NC
  BM38  GPP_D5  BI  = FM_BMC_ENABLE_N
  BM42  GPP_D4  BI  = FM_PCH_PLD_DATA_R
  BM46  VSS(56)  GROUND  = GND
  BM50  VSS(55)  GROUND  = GND
  BM54  USB3_3_TXN  BI  = TP_USB3_P03_TXN
  BM58  VSS(54)  GROUND  = GND
  BM61  USB3_6_TXP  BI  = TP_USB3_P06_TXP
  BM65  USB3_8_PCIE1_TXN  BI  = P3E_PCH_M2_TX_DN<1>
  BM69  VSS(53)  GROUND  = GND
  BM71  VSS(52)  GROUND  = GND
  BN1  VSS(476)  GROUND  = GND
  BN3  GPP_J9_LAN_I2C_SDA_MDIO_P0  BI  = SMB_PCH_MEZZ_LOM0_SDA
  BN5  VSS(48)  GROUND  = GND
  BN7  GPP_B4_CPU_GP3  BI  = IRQ_PVDDQ_ABC_VRHOT_LVT3_N
  BN11  GPP_B8_SRCCLKREQ3_N  BI  = FP_NMI_BTN_N
  BN15  GPP_B2  BI  = PU_IRQ_VRALERT_N
  BN18  GPP_B13_PLTRST_N  BI  = RST_PLTRST_N
  BN22  VSS(50)  GROUND  = GND
  BN26  RSVD(40)  UNSPEC  = TP_10GBE_KR0_MON_DP
  BN29  RSVD(37)  UNSPEC  = TP_PCH_RSVD37
  BN33  RSVD(44)  UNSPEC  = TP_10GBE_KR1_MON_DP
  BN37  VSS(57)  GROUND  = GND
  BN40  GPP_D12_SSATA_SDATAOUT1  BI  = FM_TPM_PRES_RST_N
  BN44  GPP_D23  BI  = FM_CPU0_THERMTRIP_LATCH_LVT3_N
  BN48  GPP_E10_USB2_OC1_N  BI  = IRQ_BMC_PCH_SCI_LPC_N
  BN52  VSS(47)  GROUND  = GND
  BN56  USB3_3_TXP  BI  = TP_USB3_P03_TXP
  BN59  VSS(49)  GROUND  = GND
  BN63  USB3_7_PCIE0_TXP  BI  = P3E_PCH_TX_0_DP
  BN66  VSS(46)  GROUND  = GND
  BN68  RSVD(55)  UNSPEC  = TP_PCH_RSVD55
  BN70  USB2_COMP  BI  = A_USB2_COMP
  BN72  VSS(475)  GROUND  = GND
  BP4  GPP_J2_LAN_LED_P1_0  BI  = LED_GBE_P1_0
  BP69  VSS(494)  GROUND  = GND
  BR1  VSS(464)  GROUND  = GND
  BR3  VSS(487)  GROUND  = GND
  BR6  VSS(40)  GROUND  = GND
  BR9  GPP_B3_CPU_GP2  BI  = FM_QAT_EN_N
  BR13  GPP_B7_SRCCLKREQ2_N  BI  = IRQ_PVDDQ_KLM_VRHOT_LVT3_N
  BR17  GPP_B22  BI  = FM_USB_P0_EN_BOOT_BIOS_STRAP_N
  BR20  VSS(45)  GROUND  = GND
  BR24  LAN_TX_P1P  BI  = KR_P1_OCP_TX_DP
  BR27  LAN_TX_P0P  BI  = KR_P0_OCP_TX_DP
  BR31  LAN_TX_P3N  BI  = NC
  BR35  LAN_TX_P2P  BI  = NC
  BR38  GPP_D8  BI  = FM_BMC_FAULT_LED_N
  BR42  GPP_D0  BI  = IRQ_BMC_PCH_NMI_STBY_R_N
  BR46  GPP_D22_IE_UART_TX  BI  = NC
  BR50  VSS(44)  GROUND  = GND
  BR54  VSS(42)  GROUND  = GND
  BR58  VSS(41)  GROUND  = GND
  BR61  USB3_7_PCIE0_TXN  BI  = P3E_PCH_TX_0_DN
  BR65  USB3_8_PCIE1_TXP  BI  = P3E_PCH_M2_TX_DP<1>
  BR67  USB2_VBUS  BI  = A_USB2_VBUS
  BR70  VSS(491)  GROUND  = GND
  BR72  VSS(457)  GROUND  = GND
  BT5  GPP_J12_LAN_I2C_SCL_MDC_P2  BI  = SMB_PCH_MEZZ_LOM2_SCL
  BT8  VSS(43)  GROUND  = GND
  BT66  VSS(39)  GROUND  = GND
  BT69  VSS(493)  GROUND  = GND
  BU1  VSS(465)  GROUND  = GND
  BU3  VSS(488)  GROUND  = GND
  BU6  GPP_J5_LAN_LED_P2_1  BI  = LED_GBE_P2_1
  BU9  VSS(12)  GROUND  = GND
  BU11  VSS(37)  GROUND  = GND
  BU13  VSS(38)  GROUND  = GND
  BU15  VSS(35)  GROUND  = GND
  BU18  VSS(34)  GROUND  = GND
  BU20  VSS(33)  GROUND  = GND
  BU22  VSS(32)  GROUND  = GND
  BU24  VSS(31)  GROUND  = GND
  BU26  VSS(30)  GROUND  = GND
  BU28  VSS(29)  GROUND  = GND
  BU30  VSS(28)  GROUND  = GND
  BU32  VSS(27)  GROUND  = GND
  BU34  VSS(26)  GROUND  = GND
  BU37  VSS(25)  GROUND  = GND
  BU39  VSS(24)  GROUND  = GND
  BU41  VSS(23)  GROUND  = GND
  BU43  VSS(22)  GROUND  = GND
  BU45  VSS(21)  GROUND  = GND
  BU48  VSS(20)  GROUND  = GND
  BU50  VSS(19)  GROUND  = GND
  BU52  VSS(18)  GROUND  = GND
  BU54  VSS(17)  GROUND  = GND
  BU57  VSS(16)  GROUND  = GND
  BU59  VSS(15)  GROUND  = GND
  BU61  VSS(14)  GROUND  = GND
  BU63  VSS(13)  GROUND  = GND
  BU65  USB2P_10  BI  = TP_USB2_P10_DP
  BU67  USB2P_14  BI  = TP_USB2_P14_DP
  BU70  VSS(492)  GROUND  = GND
  BU72  VSS(456)  GROUND  = GND
  BV8  GPP_J11_LAN_I2C_SDA_MDIO_P1  BI  = SMB_PCH_MEZZ_LOM1_SDA
  BV10  GPP_J16_LAN_SDP_P0_0  BI  = FM_GBE0_LVC3_MOD_ABS
  BV12  GPP_J21_LAN_SDP_P2_1  BI  = TP_PCH_GPP_J21
  BV14  GPP_J23_LAN_SDP_P3_1  BI  = TP_PCH_GPP_J23
  BV16  LAN_XTAL_IN  BI  = XTAL_KR_25M_IN
  BV19  SYS_RESET_N  BI  = RST_BMC_SYSRST_BTN_OUT_B_N
  BV21  GPP_I1_LAN_TCK  UNSPEC  = JTAG_PCH_GBE_CLK
  BV23  GPP_I6_RESET_DONE  BI  = FM_CPU1_RC_ERROR_R_N
  BV25  GPP_I10  BI  = FM_BIOS_MRC_DEBUG_MSG_DIS_N
  BV27  GPP_C1_SMBDATA  BI  = SMB_HOST_STBY_LVC3_SDA_R1
  BV29  GPP_C3_SML0CLK_IE  BI  = SMB_SMLINK0_STBY_LVC3_SCL_R1
  BV31  GPP_C10  BI  = FM_PCH_SATA_RAID_KEY
  BV33  GPP_C11  BI  = FM_BOARD_REV_ID2
  BV35  GPP_C7_SML1DATA_IE  BI  = SMB_PMBUS_BMC_STBY_LVC3_SDA_R1
  BV38  GPP_C13  BI  = FM_BOARD_REV_ID1
  BV40  VSS(11)  GROUND  = GND
  BV42  GPP_D16_SML0BALERT_IE_N  BI  = IRQ_OOB_MGMT_RISER_ALERT_N
  BV44  GPP_D21_IE_UART_RX  BI  = NC
  BV47  GPP_D10_SSATA_DEVSLP4  BI  = H_CPU0_FAST_WAKE_LVT3_N
  BV49  VSS(36)  GROUND  = GND
  BV51  CLOCKSE_PMSYNCCLK2  BI  = TP_CLK_24M_PMSYNC2
  BV53  USB2P_13  BI  = TP_USB2_P13_DP
  BV55  USB2P_9  BI  = TP_USB2_P9_DP
  BV58  USB2P_5  BI  = USB2_PCH_BMC_P5_DP_R
  BV60  USB2P_1  BI  = USB2_P01_DP
  BV62  USB2P_4  BI  = USB_PCH_BMC_P4_DP_R
  BV64  USB2P_8  BI  = TP_USB2_P8_DP
  BV66  USB2P_12  BI  = TP_USB2_P12_DP
  BW1  VSS(466)  GROUND  = GND
  BW3  RSVD(46)  UNSPEC  = TP_PCH_RSVD46
  BW5  GPP_J10_LAN_I2C_SCL_MDC_P1  BI  = SMB_PCH_MEZZ_LOM1_SCL
  BW6  GPP_J14_LAN_I2C_SCL_MDC_P3  BI  = SMB_PCH_MEZZ_LOM3_SCL
  BW9  GPP_J15_LAN_I2C_SDA_MDIO_P3  BI  = SMB_PCH_MEZZ_LOM3_SDA
  BW11  GPP_J13_LAN_I2C_SDA_MDIO_P2  BI  = SMB_PCH_MEZZ_LOM2_SDA
  BW13  GPP_J20_LAN_SDP_P2_0  BI  = FM_GBE2_LVC3_MOD_ABS
  BW15  VSS(10)  GROUND  = GND
  BW18  VSS(9)  GROUND  = GND
  BW20  GPP_I4_DO_RESET_IN_N  BI  = IRQ_DIMM_SAVE_LVT3_R_N
  BW22  GPP_I8_PCI_DIS_N  UNSPEC  = PU_10GBE_LOM_PCI_DISABLE_N
  BW24  GPP_I5_DO_RESET_OUT_N  BI  = IRQ_BOARD_BMC_ALERT_N
  BW26  VSS(8)  GROUND  = GND
  BW28  GPP_C0_SMBCLK  BI  = SMB_HOST_STBY_LVC3_SCL_R1
  BW30  GPP_C4_SML0DATA_IE  BI  = SMB_SMLINK0_STBY_LVC3_SDA_R1
  BW32  GPP_C8  BI  = FM_PASSWORD_CLEAR_N
  BW34  GPP_C5_SML0ALERT_IE_N  BI  = IRQ_SML0_ALERT_N
  BW37  GPP_C16  BI  = FM_SLT_CFG1
  BW39  GPP_C19  BI  = FM_BB_BMC_MP_GPIO
  BW41  GPP_D6  BI  = FM_CPLD_BMC_PWRDN_N
  BW43  GPP_D15_SSATA_SDATAOUT0  BI  = SGPIO_PCH_SSATA_DOUT0
  BW45  GPP_D3  BI  = IRQ_MEZZ_LAN_ALERT_N
  BW48  GPP_D17  BI  = FM_XRC_PRESENT_N
  BW50  CLOCKSE_BMCCLK  BI  = CLK_48M_USB_BMC
  BW52  VSS(7)  GROUND  = GND
  BW54  USB2P_11  BI  = TP_USB2_P11_DP
  BW57  USB2P_7  BI  = TP_USB2_P07_DP
  BW59  USB2P_3  BI  = TP_USB2_P03_DP
  BW61  USB2P_2  BI  = USB2_P02_DP_R
  BW63  USB2P_6  BI  = TP_USB2_P06_DP
  BW65  USB2N_10  BI  = TP_USB2_P10_DN
  BW67  USB2N_12  BI  = TP_USB2_P12_DN
  BW68  USB2N_14  BI  = TP_USB2_P14_DN
  BW70  VSS(455)  GROUND  = GND
  BW72  VSS(454)  GROUND  = GND
  BY10  GPP_J18_LAN_SDP_P1_0  BI  = FM_GBE1_LVC3_MOD_ABS
  BY12  GPP_J22_LAN_SDP_P3_0  BI  = FM_GBE3_LVC3_MOD_ABS
  BY14  GPP_J19_LAN_SDP_P1_1  BI  = TP_PCH_GPP_J19
  BY16  LAN_XTAL_OUT  BI  = XTAL_KR_25M_OUT
  BY19  SYS_PWROK  BI  = PWRGD_SYS_PWROK
  BY21  GPP_I9_LAN_DIS_N  UNSPEC  = FM_10GBE_LOM_DISABLE_N
  BY23  GPP_I3_LAN_TDI  UNSPEC  = JTAG_PCH_GBE_TDI
  BY25  GPIO_RCOMP_3P3  BI  = A_RCOMP_3P3
  BY27  GPP_C2_SMBALERT_N  BI  = PU_PCH_TLS_ENABLE_STRAP
  BY29  GPP_C9  BI  = FM_CPU1_RC_EN
  BY31  GPP_C17  BI  = FM_SLT_CFG2_R
  BY33  GPP_C21  BI  = FM_BIOS_POST_CMPLT_N
  BY35  GPP_C18  BI  = FM_PMBUS_ALERT_BUF_EN_R_N
  BY38  GPP_C14  BI  = IRQ_BMC_PCH_SCI_LPC_N
  BY40  VSS(6)  GROUND  = GND
  BY42  GPP_D9_SSATA_DEVSLP3  BI  = IRQ_FORCE_NM_THROTTLE_N
  BY44  GPP_D13_SML0BCLK_IE  BI  = SMB_SLOTX24_PCH_STBY_LVC3_SCL
  BY47  GPP_D11_SSATA_DEVSLP5  BI  = IRQ_LOM_ALERT_N
  BY49  VSS(5)  GROUND  = GND
  BY51  CLOCKSE_PMSYNCCLK1  BI  = H_PMSYNC_CLK_24M_R
  BY53  USB2N_13  BI  = TP_USB2_P13_DN
  BY55  USB2N_9  BI  = TP_USB2_P9_DN
  BY58  USB2N_5  BI  = USB2_PCH_BMC_P5_DN_R
  BY60  USB2N_1  BI  = USB2_P01_DN
  BY62  USB2N_4  BI  = USB_PCH_BMC_P4_DN_R
  BY64  USB2N_8  BI  = TP_USB2_P8_DN
  C3  VSS(463)  GROUND  = GND
  C5  RSVD(16)  UNSPEC  = TP_PCH_RSVD16
  C6  RSVD(15)  UNSPEC  = TP_PCH_RSVD15
  C9  RSVD(19)  UNSPEC  = TP_PCH_RSVD19
  C11  RSVD(18)  UNSPEC  = TP_PCH_RSVD18
  C13  GPD8_SUSCLK  BI  = TP_PCH_GDP8_SUSCLK
  C15  GPD3_PWRBTN_N  BI  = FM_PCH_PWRBTN_N
  C18  RSVD(11)  UNSPEC  = FM_SINT_PRSNT_N
  C20  CLKOUT_SRCN(14)  BI  = CLK_100M_SPRV_DN
  C22  VSS(437)  GROUND  = GND
  C24  CLKOUT_SRCN(13)  BI  = NC
  C26  RSVD(64)  UNSPEC  = TP_PCH_RSVD64
  C28  CLKOUT_SRCP(4)  BI  = CLK_100M_PCH_SLOTX24_S2_DP
  C30  VSS(436)  GROUND  = GND
  C32  CLKOUT_NSSCCAP0P  BI  = TP_CLK_100M_NSSCC0_DP
  C34  VSS(435)  GROUND  = GND
  C37  VSS(434)  GROUND  = GND
  C39  CLKOUT_ITPXDPP  BI  = CLK_100M_PCH_XDP_DP
  C41  VSS(433)  GROUND  = GND
  C43  DMI_RXN(1)  BI  = DMI_CPU0_PCH_TX_C_DN<1>
  C45  DMI_RXN(3)  BI  = DMI_CPU0_PCH_TX_C_DN<3>
  C48  PCIEUP_0_RXN  BI  = P3E_CPU0_PE1_PCH_TXN<0>
  C50  PCIEUP_2_RXN  BI  = P3E_CPU0_PE1_PCH_TXN<2>
  C52  PCIEUP_4_RXN  BI  = P3E_CPU0_PE1_PCH_TXN<4>
  C54  PCIEUP_6_RXN  BI  = P3E_CPU0_PE1_PCH_TXN<6>
  C57  PCIEUP_8_RXN  BI  = P3E_CPU0_PE1_PCH_C_TXP<8>
  C59  PCIEUP_10_RXN  BI  = P3E_CPU0_PE1_PCH_C_TXP<10>
  C61  PCIEUP_12_RXN  BI  = P3E_CPU0_PE1_PCH_C_TXP<12>
  C63  PCIEUP_14_RXN  BI  = P3E_CPU0_PE1_PCH_C_TXP<14>
  C65  VSS(432)  GROUND  = GND
  C67  RSVD(13)  UNSPEC  = TP_PCH_RSVD13
  C68  RSVD(12)  UNSPEC  = TP_PCH_RSVD12
  C70  CGC_DUT_DETECT_N  BI  = FM_PCH_PRSNT_N
  C72  VSS(462)  GROUND  = GND
  CA3  VSS(467)  GROUND  = GND
  CA5  VSS(469)  GROUND  = GND
  CA7  VSS(470)  GROUND  = GND
  CA9  VSS(471)  GROUND  = GND
